# BASEBOARD_FAB2 (Tioga Pass) — schematic netlist excerpt (pin names and nets, part order shuffled) for the footprints in the layout excerpt that follows; sources: Cadence DE-HDL packaged netlist, KiCad conversion of Wiwynn_Tioga_Pass_MB.brd

C6L12  CAP  4.7UF 6.3V 10% X6S  pkg 0603  page 234 : A = VR_VB_PVPP_KLM ; B = AGND_PVPP_KLM
C5U13  CAP  100UF 4V 20% X5R  pkg 0805  page 217 : A = PVDDQ_ABC ; B = GND
C6U13  CAP  10UF 4V 20% X6S  pkg 0603LF  page 229 : A = PVDDQ_GHJ ; B = GND

(kicad_pcb
	(version 20260206)
	(generator "pcbnew")
	(generator_version "10.0")
	(general
		(thickness 1.6)
		(legacy_teardrops no)
	)
	(paper "A4")
	(title_block
		(title "Wiwynn_Tioga_Pass_MB.brd")
		(comment 1 "Tioga Pass / footprints 3603-3605 of 4770")
	)
	(layers
		(0 "F.Cu" signal "TOP")
		(4 "In1.Cu" signal "L2GND")
		(6 "In2.Cu" signal "L3")
		(8 "In3.Cu" signal "L4GND")
		(10 "In4.Cu" signal "L5")
		(12 "In5.Cu" signal "L6GND")
		(14 "In6.Cu" signal "L7VCC")
		(16 "In7.Cu" signal "L8VCC")
		(18 "In8.Cu" signal "L9GND")
		(20 "In9.Cu" signal "L10")
		(22 "In10.Cu" signal "L11GND")
		(24 "In11.Cu" signal "L12")
		(26 "In12.Cu" signal "L13GND")
		(2 "B.Cu" signal "BOTTOM")
		(9 "F.Adhes" user "F.Adhesive")
		(11 "B.Adhes" user "B.Adhesive")
		(13 "F.Paste" user "Package Geometry/Pastemask Top")
		(15 "B.Paste" user "Package Geometry/Pastemask Bottom")
		(5 "F.SilkS" user "Ref Des/Silkscreen Top")
		(7 "B.SilkS" user "Ref Des/Silkscreen Bottom")
		(1 "F.Mask" user "Board Geometry/Soldermask Top")
		(3 "B.Mask" user "Board Geometry/Soldermask Bottom")
		(17 "Dwgs.User" user "User.Drawings")
		(19 "Cmts.User" user "User.Comments")
		(21 "Eco1.User" user "User.Eco1")
		(23 "Eco2.User" user "User.Eco2")
		(25 "Edge.Cuts" user "Board Geometry/Outline")
		(27 "Margin" user)
		(31 "F.CrtYd" user "Package Geometry/Place Bound Top")
		(29 "B.CrtYd" user "Package Geometry/Place Bound Bottom")
		(35 "F.Fab" user "Ref Des/Assembly Top")
		(33 "B.Fab" user "Ref Des/Assembly Bottom")
	)
	(footprint ""
		(layer "B.Cu")
		(at 274.066 3.81 90)
		(property "Reference" "C5U13"
			(at 0 0 90)
			(layer "B.SilkS")
			(hide yes)
			(effects
				(font
					(size 1.27 1.27)
				)
				(justify mirror)
			)
		)
		(property "Value" ""
			(at 0 0 90)
			(layer "B.Fab")
			(effects
				(font
					(size 1.27 1.27)
				)
				(justify mirror)
			)
		)
		(duplicate_pad_numbers_are_jumpers no)
		(fp_rect
			(start -0.7239 -0.2159)
			(end 0.7239 1.9939)
			(stroke
				(width 0)
				(type default)
			)
			(fill no)
			(layer "B.CrtYd")
		)
		(fp_line
			(start 0.7239 -0.2159)
			(end 0.7239 1.9939)
			(stroke
				(width 0.1)
				(type default)
			)
			(layer "B.Fab")
		)
		(fp_line
			(start -0.7239 -0.2159)
			(end 0.7239 -0.2159)
			(stroke
				(width 0.1)
				(type default)
			)
			(layer "B.Fab")
		)
		(fp_line
			(start 0.7239 1.9939)
			(end -0.7239 1.9939)
			(stroke
				(width 0.1)
				(type default)
			)
			(layer "B.Fab")
		)
		(fp_line
			(start -0.7239 1.9939)
			(end -0.7239 -0.2159)
			(stroke
				(width 0.1)
				(type default)
			)
			(layer "B.Fab")
		)
		(pad "1" smd rect
			(at 0 0 270)
			(size 1.27 1.016)
			(layers "B.Cu" "B.Mask" "B.Paste")
			(net "PVDDQ_ABC")
		)
		(pad "2" smd rect
			(at 0 1.778 270)
			(size 1.27 1.016)
			(layers "B.Cu" "B.Mask" "B.Paste")
			(net "GND")
		)
		(zone
			(layer "B.Cu")
			(hatch none 0.5)
			(connect_pads
				(clearance 0)
			)
			(min_thickness 0.25)
			(keepout
				(tracks not_allowed)
				(vias allowed)
				(pads allowed)
				(copperpour not_allowed)
				(footprints allowed)
			)
			(placement
				(enabled no)
				(sheetname "")
			)
			(fill
				(thermal_gap 0.5)
				(thermal_bridge_width 0.5)
				(island_removal_mode 0)
			)
			(polygon
				(pts
					(xy 274.574 4.445) (xy 275.336 4.445) (xy 275.336 3.175) (xy 274.574 3.175)
				)
			)
		)
	)
	(footprint ""
		(layer "B.Cu")
		(at 172.6692 -135.636)
		(property "Reference" "C6L12"
			(at 0 0 0)
			(layer "B.SilkS")
			(hide yes)
			(effects
				(font
					(size 1.27 1.27)
				)
				(justify mirror)
			)
		)
		(property "Value" ""
			(at 0 0 0)
			(layer "B.Fab")
			(effects
				(font
					(size 1.27 1.27)
				)
				(justify mirror)
			)
		)
		(duplicate_pad_numbers_are_jumpers no)
		(fp_poly
			(pts
				(xy 0.4953 -0.2032) (xy -0.4953 -0.2032) (xy -0.4953 1.6002) (xy 0.4953 1.6002)
			)
			(stroke
				(width 0)
				(type default)
			)
			(fill no)
			(layer "B.CrtYd")
		)
		(fp_line
			(start -0.4953 -0.2032)
			(end -0.4953 1.6002)
			(stroke
				(width 0.1)
				(type default)
			)
			(layer "B.Fab")
		)
		(fp_line
			(start -0.4953 1.6002)
			(end 0.4953 1.6002)
			(stroke
				(width 0.1)
				(type default)
			)
			(layer "B.Fab")
		)
		(fp_line
			(start 0.4953 -0.2032)
			(end -0.4953 -0.2032)
			(stroke
				(width 0.1)
				(type default)
			)
			(layer "B.Fab")
		)
		(fp_line
			(start 0.4953 1.6002)
			(end 0.4953 -0.2032)
			(stroke
				(width 0.1)
				(type default)
			)
			(layer "B.Fab")
		)
		(pad "1" smd rect
			(at 0 0 180)
			(size 0.762 0.889)
			(layers "B.Cu" "B.Mask" "B.Paste")
			(net "VR_VB_PVPP_KLM")
		)
		(pad "2" smd rect
			(at 0 1.397 180)
			(size 0.762 0.889)
			(layers "B.Cu" "B.Mask" "B.Paste")
			(net "AGND_PVPP_KLM")
		)
		(zone
			(layer "B.Cu")
			(hatch none 0.5)
			(connect_pads
				(clearance 0)
			)
			(min_thickness 0.25)
			(keepout
				(tracks not_allowed)
				(vias allowed)
				(pads allowed)
				(copperpour not_allowed)
				(footprints allowed)
			)
			(placement
				(enabled no)
				(sheetname "")
			)
			(fill
				(thermal_gap 0.5)
				(thermal_bridge_width 0.5)
				(island_removal_mode 0)
			)
			(polygon
				(pts
					(xy 173.0502 -135.1915) (xy 172.2882 -135.1915) (xy 172.2882 -134.6835) (xy 173.0502 -134.6835)
				)
			)
		)
	)
	(footprint ""
		(layer "B.Cu")
		(at 169.037 -4.699 90)
		(property "Reference" "C6U13"
			(at 0 0 90)
			(layer "B.SilkS")
			(hide yes)
			(effects
				(font
					(size 1.27 1.27)
				)
				(justify mirror)
			)
		)
		(property "Value" ""
			(at 0 0 90)
			(layer "B.Fab")
			(effects
				(font
					(size 1.27 1.27)
				)
				(justify mirror)
			)
		)
		(duplicate_pad_numbers_are_jumpers no)
		(fp_rect
			(start 0.4953 1.6002)
			(end -0.4953 -0.2032)
			(stroke
				(width 0)
				(type default)
			)
			(fill no)
			(layer "B.CrtYd")
		)
		(fp_line
			(start 0.4953 -0.2032)
			(end -0.4953 -0.2032)
			(stroke
				(width 0.1)
				(type default)
			)
			(layer "B.Fab")
		)
		(fp_line
			(start -0.4953 -0.2032)
			(end -0.4953 1.6002)
			(stroke
				(width 0.1)
				(type default)
			)
			(layer "B.Fab")
		)
		(fp_line
			(start 0.4953 1.6002)
			(end 0.4953 -0.2032)
			(stroke
				(width 0.1)
				(type default)
			)
			(layer "B.Fab")
		)
		(fp_line
			(start -0.4953 1.6002)
			(end 0.4953 1.6002)
			(stroke
				(width 0.1)
				(type default)
			)
			(layer "B.Fab")
		)
		(pad "1" smd rect
			(at 0 0 270)
			(size 0.762 0.889)
			(layers "B.Cu" "B.Mask" "B.Paste")
			(net "PVDDQ_GHJ")
		)
		(pad "2" smd rect
			(at 0 1.397 270)
			(size 0.762 0.889)
			(layers "B.Cu" "B.Mask" "B.Paste")
			(net "GND")
		)
		(zone
			(layer "B.Cu")
			(hatch none 0.5)
			(connect_pads
				(clearance 0)
			)
			(min_thickness 0.25)
			(keepout
				(tracks not_allowed)
				(vias allowed)
				(pads allowed)
				(copperpour not_allowed)
				(footprints allowed)
			)
			(placement
				(enabled no)
				(sheetname "")
			)
			(fill
				(thermal_gap 0.5)
				(thermal_bridge_width 0.5)
				(island_removal_mode 0)
			)
			(polygon
				(pts
					(xy 169.9895 -5.08) (xy 169.4815 -5.08) (xy 169.4815 -4.318) (xy 169.9895 -4.318)
				)
			)
		)
	)
)
